(kicad_pcb
	(version 20241229)
	(generator "pcbnew")
	(generator_version "9.0")
	(general
		(thickness 1.6296)
		(legacy_teardrops no)
	)
	(paper "A3")
	(title_block
		(title "Thunderbolt to 10GbE adapter")
		(date "2026-04-21")
		(rev "1.1.0")
		(company "Antmicro Ltd")
		(comment 1 "www.antmicro.com")
		(comment 9 "footprints 23-27 of 703")
	)
	(layers
		(0 "F.Cu" signal)
		(4 "In1.Cu" signal)
		(6 "In2.Cu" signal)
		(8 "In3.Cu" signal)
		(10 "In4.Cu" signal)
		(12 "In5.Cu" signal)
		(14 "In6.Cu" signal)
		(2 "B.Cu" signal)
		(9 "F.Adhes" user "F.Adhesive")
		(11 "B.Adhes" user "B.Adhesive")
		(13 "F.Paste" user)
		(15 "B.Paste" user)
		(5 "F.SilkS" user "F.Silkscreen")
		(7 "B.SilkS" user "B.Silkscreen")
		(1 "F.Mask" user)
		(3 "B.Mask" user)
		(17 "Dwgs.User" user "User.Drawings")
		(19 "Cmts.User" user "User.Comments")
		(21 "Eco1.User" user "User.Eco1")
		(23 "Eco2.User" user "User.Eco2")
		(25 "Edge.Cuts" user)
		(27 "Margin" user)
		(31 "F.CrtYd" user "F.Courtyard")
		(29 "B.CrtYd" user "B.Courtyard")
		(35 "F.Fab" user)
		(33 "B.Fab" user)
	)
	(footprint "antmicro-footprints:TDFN-8-1EP_2x3x0.75mm_P0.5mm_EP1.75x1.63mm"
		(layer "F.Cu")
		(at 120.5 71)
		(descr "8-Lead Plastic Dual Flat, 2x3mm Body")
		(tags "DFN 0.5")
		(property "Reference" "U18"
			(at -2.2 2.3 0)
			(layer "F.SilkS")
			(effects
				(font
					(size 0.7 0.7)
					(thickness 0.15)
				)
				(justify left bottom)
			)
		)
		(property "Value" "MAX31740ATA+T"
			(at -2.1 3 0)
			(layer "F.Fab")
			(effects
				(font
					(size 0.7 0.7)
					(thickness 0.15)
				)
				(justify left bottom)
			)
		)
		(property "Datasheet" "https://www.analog.com/media/en/technical-documentation/data-sheets/max31740.pdf"
			(at 0 0 0)
			(layer "F.Fab")
			(hide yes)
			(effects
				(font
					(size 1.27 1.27)
					(thickness 0.15)
				)
			)
		)
		(property "Description" "Pwm fan speed controller, temperature measurement, Control speed of 2-, 3-, 4- Wire Fans"
			(at 0 0 0)
			(layer "F.Fab")
			(hide yes)
			(effects
				(font
					(size 1.27 1.27)
					(thickness 0.15)
				)
			)
		)
		(property "MPN" "MAX31740ATA+T"
			(at 0 0 0)
			(unlocked yes)
			(layer "F.Fab")
			(hide yes)
			(effects
				(font
					(size 1 1)
					(thickness 0.15)
				)
			)
		)
		(property "Manufacturer" "Analog Devices"
			(at 0 0 0)
			(unlocked yes)
			(layer "F.Fab")
			(hide yes)
			(effects
				(font
					(size 1 1)
					(thickness 0.15)
				)
			)
		)
		(property "Author" "Antmicro"
			(at 0 0 0)
			(unlocked yes)
			(layer "F.Fab")
			(hide yes)
			(effects
				(font
					(size 1 1)
					(thickness 0.15)
				)
			)
		)
		(property "License" "Apache-2.0"
			(at 0 0 0)
			(unlocked yes)
			(layer "F.Fab")
			(hide yes)
			(effects
				(font
					(size 1 1)
					(thickness 0.15)
				)
			)
		)
		(sheetname "/Fan controller/")
		(sheetfile "fan-controller.kicad_sch")
		(attr smd)
		(fp_circle
			(center -1.8 -1.1)
			(end -1.75 -1.1)
			(stroke
				(width 0.15)
				(type solid)
			)
			(fill yes)
			(layer "F.SilkS")
		)
		(fp_rect
			(start -2.05 -1.25)
			(end 2.05 1.25)
			(stroke
				(width 0.05)
				(type default)
			)
			(fill no)
			(layer "F.CrtYd")
		)
		(fp_text user "${REFERENCE}"
			(at -2.12 6.2 0)
			(layer "F.Fab")
			(effects
				(font
					(size 0.7 0.7)
					(thickness 0.15)
				)
				(justify left bottom)
			)
		)
		(fp_text user "License: Apache-2.0"
			(at -2.12 5 0)
			(layer "F.Fab")
			(effects
				(font
					(size 0.7 0.7)
					(thickness 0.15)
				)
				(justify left bottom)
			)
		)
		(fp_text user "Author: Antmicro"
			(at -2.12 7.4 0)
			(layer "F.Fab")
			(effects
				(font
					(size 0.7 0.7)
					(thickness 0.15)
				)
				(justify left bottom)
			)
		)
		(pad "1" smd rect
			(at -1.5 -0.75 90)
			(size 0.3 0.75)
			(layers "F.Cu" "F.Mask" "F.Paste")
			(net 157 "/Fan controller/DMIN")
			(pinfunction "DMIN")
			(pintype "passive")
		)
		(pad "2" smd rect
			(at -1.5 -0.25 90)
			(size 0.3 0.75)
			(layers "F.Cu" "F.Mask" "F.Paste")
			(net 158 "/Fan controller/SLOPE")
			(pinfunction "SLOPE")
			(pintype "passive")
		)
		(pad "3" smd rect
			(at -1.5 0.25 90)
			(size 0.3 0.75)
			(layers "F.Cu" "F.Mask" "F.Paste")
			(net 151 "/Fan controller/SENSE")
			(pinfunction "SENSE")
			(pintype "passive")
		)
		(pad "4" smd rect
			(at -1.5 0.75 90)
			(size 0.3 0.75)
			(layers "F.Cu" "F.Mask" "F.Paste")
			(net 23 "GND")
			(pinfunction "GND")
			(pintype "power_in")
		)
		(pad "5" smd rect
			(at 1.5 0.75 90)
			(size 0.3 0.75)
			(layers "F.Cu" "F.Mask" "F.Paste")
			(net 152 "/Fan controller/FREQ")
			(pinfunction "FREQ")
			(pintype "passive")
		)
		(pad "6" smd rect
			(at 1.5 0.25 90)
			(size 0.3 0.75)
			(layers "F.Cu" "F.Mask" "F.Paste")
			(net 156 "/Fan controller/D0")
			(pinfunction "D0")
			(pintype "passive")
		)
		(pad "7" smd rect
			(at 1.5 -0.25 90)
			(size 0.3 0.75)
			(layers "F.Cu" "F.Mask" "F.Paste")
			(net 154 "/Fan controller/PWM")
			(pinfunction "PWM_OUT")
			(pintype "output")
		)
		(pad "8" smd rect
			(at 1.5 -0.75 90)
			(size 0.3 0.75)
			(layers "F.Cu" "F.Mask" "F.Paste")
			(net 40 "+5V")
			(pinfunction "VDD")
			(pintype "power_in")
		)
		(pad "9" smd rect
			(at 0 0 90)
			(size 1.63 1.75)
			(layers "F.Cu" "F.Mask" "F.Paste")
			(net 23 "GND")
			(pinfunction "EP")
			(pintype "power_in")
		)
	)
	(footprint "antmicro-footprints:C_0805_2012Metric"
		(layer "F.Cu")
		(at 161.394999 97.024998 180)
		(descr "Capacitor SMD 0805")
		(tags "capacitor SMD 0805")
		(property "Reference" "C170"
			(at -7.695 0 180)
			(layer "F.SilkS")
			(effects
				(font
					(size 0.7 0.7)
					(thickness 0.15)
				)
			)
		)
		(property "Value" "C_100u_0805"
			(at -2.055717 1.963152 180)
			(layer "F.Fab")
			(effects
				(font
					(size 0.7 0.7)
					(thickness 0.15)
				)
				(justify left bottom)
			)
		)
		(property "Datasheet" "https://www.murata.com/products/productdetail?partno=GRM21BR60J107ME15%23"
			(at 0 0 180)
			(layer "F.Fab")
			(hide yes)
			(effects
				(font
					(size 1.27 1.27)
					(thickness 0.15)
				)
			)
		)
		(property "Description" "SMD Multilayer Ceramic Capacitor, 100 µF, 6.3 V, 0805 [2012 Metric], ± 20%, X5R, GRM Series"
			(at 0 0 180)
			(layer "F.Fab")
			(hide yes)
			(effects
				(font
					(size 1.27 1.27)
					(thickness 0.15)
				)
			)
		)
		(property "MPN" "GRM21BR60J107ME15L"
			(at 0 0 180)
			(unlocked yes)
			(layer "F.Fab")
			(hide yes)
			(effects
				(font
					(size 1 1)
					(thickness 0.15)
				)
			)
		)
		(property "Manufacturer" "Murata"
			(at 0 0 180)
			(unlocked yes)
			(layer "F.Fab")
			(hide yes)
			(effects
				(font
					(size 1 1)
					(thickness 0.15)
				)
			)
		)
		(property "License" "Apache-2.0"
			(at 0 0 180)
			(unlocked yes)
			(layer "F.Fab")
			(hide yes)
			(effects
				(font
					(size 1 1)
					(thickness 0.15)
				)
			)
		)
		(property "Author" "Antmicro"
			(at 0 0 180)
			(unlocked yes)
			(layer "F.Fab")
			(hide yes)
			(effects
				(font
					(size 1 1)
					(thickness 0.15)
				)
			)
		)
		(property "Val" "100u"
			(at 0 0 180)
			(unlocked yes)
			(layer "F.Fab")
			(hide yes)
			(effects
				(font
					(size 1 1)
					(thickness 0.15)
				)
			)
		)
		(property "Voltage" ""
			(at 0 0 180)
			(unlocked yes)
			(layer "F.Fab")
			(hide yes)
			(effects
				(font
					(size 1 1)
					(thickness 0.15)
				)
			)
		)
		(property "Dielectric" ""
			(at 0 0 180)
			(unlocked yes)
			(layer "F.Fab")
			(hide yes)
			(effects
				(font
					(size 1 1)
					(thickness 0.15)
				)
			)
		)
		(property "Public" "False"
			(at 0 0 180)
			(unlocked yes)
			(layer "F.Fab")
			(hide yes)
			(effects
				(font
					(size 1 1)
					(thickness 0.15)
				)
			)
		)
		(sheetname "/X710-AT2 power/")
		(sheetfile "x710-at2-power.kicad_sch")
		(attr smd)
		(fp_line
			(start -0.3 0.7)
			(end 0.3 0.7)
			(stroke
				(width 0.15)
				(type solid)
			)
			(layer "F.SilkS")
		)
		(fp_line
			(start -0.3 -0.7)
			(end 0.3 -0.7)
			(stroke
				(width 0.15)
				(type solid)
			)
			(layer "F.SilkS")
		)
		(fp_rect
			(start 1.95 -0.9)
			(end -1.95 0.9)
			(stroke
				(width 0.05)
				(type default)
			)
			(fill no)
			(layer "F.CrtYd")
		)
		(fp_rect
			(start -0.95 -0.675)
			(end 0.95 0.675)
			(stroke
				(width 0.15)
				(type solid)
			)
			(fill no)
			(layer "F.Fab")
		)
		(fp_text user "${REFERENCE}"
			(at -1.9 3.947 180)
			(layer "F.Fab")
			(effects
				(font
					(size 0.7 0.7)
					(thickness 0.15)
				)
				(justify left bottom)
			)
		)
		(fp_text user "License: Apache-2.0"
			(at -1.9 4.947 180)
			(layer "F.Fab")
			(effects
				(font
					(size 0.7 0.7)
					(thickness 0.15)
				)
				(justify left bottom)
			)
		)
		(fp_text user "Author: Antmicro"
			(at -1.9 5.947 180)
			(layer "F.Fab")
			(effects
				(font
					(size 0.7 0.7)
					(thickness 0.15)
				)
				(justify left bottom)
			)
		)
		(pad "1" smd roundrect
			(at -1.1 0 180)
			(size 1.2 1.3)
			(layers "F.Cu" "F.Mask" "F.Paste")
			(roundrect_rratio 0.25)
			(net 23 "GND")
			(pintype "passive")
		)
		(pad "2" smd roundrect
			(at 1.1 0 180)
			(size 1.2 1.3)
			(layers "F.Cu" "F.Mask" "F.Paste")
			(roundrect_rratio 0.25)
			(net 5 "P0_AVDDL")
			(pintype "passive")
		)
	)
	(footprint "antmicro-footprints:R_0402_1005Metric"
		(layer "F.Cu")
		(at 117.6 114.42 -90)
		(descr "Resistor SMD 0402")
		(tags "resistor SMD 0402")
		(property "Reference" "R32"
			(at 1.98 -0.65 270)
			(layer "F.SilkS")
			(effects
				(font
					(size 0.7 0.7)
					(thickness 0.15)
				)
			)
		)
		(property "Value" "R_330R_0402"
			(at -1.011843 1.772047 270)
			(layer "F.Fab")
			(effects
				(font
					(size 0.7 0.7)
					(thickness 0.15)
				)
				(justify left bottom)
			)
		)
		(property "Datasheet" "https://www.bourns.com/docs/product-datasheets/cr.pdf"
			(at 0 0 270)
			(layer "F.Fab")
			(hide yes)
			(effects
				(font
					(size 1.27 1.27)
					(thickness 0.15)
				)
			)
		)
		(property "Description" "SMD Chip Resistor, 330 ohm, ± 1%, 62.5 mW, 0402 [1005 Metric], Thick Film, General Purpose"
			(at 0 0 270)
			(layer "F.Fab")
			(hide yes)
			(effects
				(font
					(size 1.27 1.27)
					(thickness 0.15)
				)
			)
		)
		(property "MPN" "CR0402-FX-3300GLF"
			(at 0 0 270)
			(unlocked yes)
			(layer "F.Fab")
			(hide yes)
			(effects
				(font
					(size 1 1)
					(thickness 0.15)
				)
			)
		)
		(property "Manufacturer" "Bourns"
			(at 0 0 270)
			(unlocked yes)
			(layer "F.Fab")
			(hide yes)
			(effects
				(font
					(size 1 1)
					(thickness 0.15)
				)
			)
		)
		(property "License" "Apache-2.0"
			(at 0 0 270)
			(unlocked yes)
			(layer "F.Fab")
			(hide yes)
			(effects
				(font
					(size 1 1)
					(thickness 0.15)
				)
			)
		)
		(property "Val" "330R"
			(at 0 0 270)
			(unlocked yes)
			(layer "F.Fab")
			(hide yes)
			(effects
				(font
					(size 1 1)
					(thickness 0.15)
				)
			)
		)
		(property "Tolerance" "1%"
			(at 0 0 270)
			(unlocked yes)
			(layer "F.Fab")
			(hide yes)
			(effects
				(font
					(size 1 1)
					(thickness 0.15)
				)
			)
		)
		(property "Author" "Antmicro"
			(at 0 0 270)
			(unlocked yes)
			(layer "F.Fab")
			(hide yes)
			(effects
				(font
					(size 1 1)
					(thickness 0.15)
				)
			)
		)
		(sheetname "/PD and TB DC-DC/")
		(sheetfile "PD_and_TB_DC_DC.kicad_sch")
		(attr smd)
		(fp_rect
			(start -0.925 -0.47)
			(end 0.925 0.47)
			(stroke
				(width 0.05)
				(type default)
			)
			(fill no)
			(layer "F.CrtYd")
		)
		(fp_rect
			(start -0.5 -0.25)
			(end 0.5 0.25)
			(stroke
				(width 0.15)
				(type solid)
			)
			(fill no)
			(layer "F.Fab")
		)
		(fp_text user "Author: Antmicro"
			(at -0.95 4.169 270)
			(layer "F.Fab")
			(effects
				(font
					(size 0.7 0.7)
					(thickness 0.15)
				)
				(justify left bottom)
			)
		)
		(fp_text user "${REFERENCE}"
			(at -0.95 3.168 270)
			(layer "F.Fab")
			(effects
				(font
					(size 0.7 0.7)
					(thickness 0.15)
				)
				(justify left bottom)
			)
		)
		(fp_text user "License: Apache-2.0"
			(at -0.95 5.169 270)
			(layer "F.Fab")
			(effects
				(font
					(size 0.7 0.7)
					(thickness 0.15)
				)
				(justify left bottom)
			)
		)
		(pad "1" smd roundrect
			(at -0.48 0 270)
			(size 0.59 0.64)
			(layers "F.Cu" "F.Mask" "F.Paste")
			(roundrect_rratio 0.25)
			(net 23 "GND")
			(pintype "passive")
		)
		(pad "2" smd roundrect
			(at 0.48 0 270)
			(size 0.59 0.64)
			(layers "F.Cu" "F.Mask" "F.Paste")
			(roundrect_rratio 0.25)
			(net 195 "Net-(D4-C)")
			(pintype "passive")
		)
	)
	(footprint "antmicro-footprints:C_0805_2012Metric"
		(layer "F.Cu")
		(at 161.395 95.174999 180)
		(descr "Capacitor SMD 0805")
		(tags "capacitor SMD 0805")
		(property "Reference" "C178"
			(at -7.695 0 180)
			(layer "F.SilkS")
			(effects
				(font
					(size 0.7 0.7)
					(thickness 0.15)
				)
			)
		)
		(property "Value" "C_100u_0805"
			(at -2.055717 1.963152 180)
			(layer "F.Fab")
			(effects
				(font
					(size 0.7 0.7)
					(thickness 0.15)
				)
				(justify left bottom)
			)
		)
		(property "Datasheet" "https://www.murata.com/products/productdetail?partno=GRM21BR60J107ME15%23"
			(at 0 0 180)
			(layer "F.Fab")
			(hide yes)
			(effects
				(font
					(size 1.27 1.27)
					(thickness 0.15)
				)
			)
		)
		(property "Description" "SMD Multilayer Ceramic Capacitor, 100 µF, 6.3 V, 0805 [2012 Metric], ± 20%, X5R, GRM Series"
			(at 0 0 180)
			(layer "F.Fab")
			(hide yes)
			(effects
				(font
					(size 1.27 1.27)
					(thickness 0.15)
				)
			)
		)
		(property "MPN" "GRM21BR60J107ME15L"
			(at 0 0 180)
			(unlocked yes)
			(layer "F.Fab")
			(hide yes)
			(effects
				(font
					(size 1 1)
					(thickness 0.15)
				)
			)
		)
		(property "Manufacturer" "Murata"
			(at 0 0 180)
			(unlocked yes)
			(layer "F.Fab")
			(hide yes)
			(effects
				(font
					(size 1 1)
					(thickness 0.15)
				)
			)
		)
		(property "License" "Apache-2.0"
			(at 0 0 180)
			(unlocked yes)
			(layer "F.Fab")
			(hide yes)
			(effects
				(font
					(size 1 1)
					(thickness 0.15)
				)
			)
		)
		(property "Author" "Antmicro"
			(at 0 0 180)
			(unlocked yes)
			(layer "F.Fab")
			(hide yes)
			(effects
				(font
					(size 1 1)
					(thickness 0.15)
				)
			)
		)
		(property "Val" "100u"
			(at 0 0 180)
			(unlocked yes)
			(layer "F.Fab")
			(hide yes)
			(effects
				(font
					(size 1 1)
					(thickness 0.15)
				)
			)
		)
		(property "Voltage" ""
			(at 0 0 180)
			(unlocked yes)
			(layer "F.Fab")
			(hide yes)
			(effects
				(font
					(size 1 1)
					(thickness 0.15)
				)
			)
		)
		(property "Dielectric" ""
			(at 0 0 180)
			(unlocked yes)
			(layer "F.Fab")
			(hide yes)
			(effects
				(font
					(size 1 1)
					(thickness 0.15)
				)
			)
		)
		(property "Public" "False"
			(at 0 0 180)
			(unlocked yes)
			(layer "F.Fab")
			(hide yes)
			(effects
				(font
					(size 1 1)
					(thickness 0.15)
				)
			)
		)
		(sheetname "/X710-AT2 power/")
		(sheetfile "x710-at2-power.kicad_sch")
		(attr smd)
		(fp_line
			(start -0.3 0.7)
			(end 0.3 0.7)
			(stroke
				(width 0.15)
				(type solid)
			)
			(layer "F.SilkS")
		)
		(fp_line
			(start -0.3 -0.7)
			(end 0.3 -0.7)
			(stroke
				(width 0.15)
				(type solid)
			)
			(layer "F.SilkS")
		)
		(fp_rect
			(start 1.95 -0.9)
			(end -1.95 0.9)
			(stroke
				(width 0.05)
				(type default)
			)
			(fill no)
			(layer "F.CrtYd")
		)
		(fp_rect
			(start -0.95 -0.675)
			(end 0.95 0.675)
			(stroke
				(width 0.15)
				(type solid)
			)
			(fill no)
			(layer "F.Fab")
		)
		(fp_text user "${REFERENCE}"
			(at -1.9 3.947 180)
			(layer "F.Fab")
			(effects
				(font
					(size 0.7 0.7)
					(thickness 0.15)
				)
				(justify left bottom)
			)
		)
		(fp_text user "License: Apache-2.0"
			(at -1.9 4.947 180)
			(layer "F.Fab")
			(effects
				(font
					(size 0.7 0.7)
					(thickness 0.15)
				)
				(justify left bottom)
			)
		)
		(fp_text user "Author: Antmicro"
			(at -1.9 5.947 180)
			(layer "F.Fab")
			(effects
				(font
					(size 0.7 0.7)
					(thickness 0.15)
				)
				(justify left bottom)
			)
		)
		(pad "1" smd roundrect
			(at -1.1 0 180)
			(size 1.2 1.3)
			(layers "F.Cu" "F.Mask" "F.Paste")
			(roundrect_rratio 0.25)
			(net 23 "GND")
			(pintype "passive")
		)
		(pad "2" smd roundrect
			(at 1.1 0 180)
			(size 1.2 1.3)
			(layers "F.Cu" "F.Mask" "F.Paste")
			(roundrect_rratio 0.25)
			(net 5 "P0_AVDDL")
			(pintype "passive")
		)
	)
	(footprint "antmicro-footprints:R_0402_1005Metric"
		(layer "F.Cu")
		(at 132.4 82.8 -90)
		(descr "Resistor SMD 0402")
		(tags "resistor SMD 0402")
		(property "Reference" "R225"
			(at 1.6 0.6 270)
			(layer "F.SilkS")
			(effects
				(font
					(size 0.7 0.7)
					(thickness 0.15)
				)
				(justify left bottom)
			)
		)
		(property "Value" "R_10k_0402"
			(at -1.011843 1.772047 270)
			(layer "F.Fab")
			(effects
				(font
					(size 0.7 0.7)
					(thickness 0.15)
				)
				(justify left bottom)
			)
		)
		(property "Datasheet" "https://www.bourns.com/docs/product-datasheets/cr.pdf"
			(at 0 0 270)
			(layer "F.Fab")
			(hide yes)
			(effects
				(font
					(size 1.27 1.27)
					(thickness 0.15)
				)
			)
		)
		(property "Description" "SMD Chip Resistor, 10 kohm, ± 1%, 62.5 mW, 0402 [1005 Metric], Thick Film, General Purpose"
			(at 0 0 270)
			(layer "F.Fab")
			(hide yes)
			(effects
				(font
					(size 1.27 1.27)
					(thickness 0.15)
				)
			)
		)
		(property "MPN" "CR0402-FX-1002GLF"
			(at 0 0 270)
			(unlocked yes)
			(layer "F.Fab")
			(hide yes)
			(effects
				(font
					(size 1 1)
					(thickness 0.15)
				)
			)
		)
		(property "Manufacturer" "Bourns"
			(at 0 0 270)
			(unlocked yes)
			(layer "F.Fab")
			(hide yes)
			(effects
				(font
					(size 1 1)
					(thickness 0.15)
				)
			)
		)
		(property "License" "Apache-2.0"
			(at 0 0 270)
			(unlocked yes)
			(layer "F.Fab")
			(hide yes)
			(effects
				(font
					(size 1 1)
					(thickness 0.15)
				)
			)
		)
		(property "Author" "Antmicro"
			(at 0 0 270)
			(unlocked yes)
			(layer "F.Fab")
			(hide yes)
			(effects
				(font
					(size 1 1)
					(thickness 0.15)
				)
			)
		)
		(property "Val" "10k"
			(at 0 0 270)
			(unlocked yes)
			(layer "F.Fab")
			(hide yes)
			(effects
				(font
					(size 1 1)
					(thickness 0.15)
				)
			)
		)
		(property "Tolerance" "1%"
			(at 0 0 270)
			(unlocked yes)
			(layer "F.Fab")
			(hide yes)
			(effects
				(font
					(size 1 1)
					(thickness 0.15)
				)
			)
		)
		(sheetname "/X710 flash memory/")
		(sheetfile "flash_x710.kicad_sch")
		(attr smd)
		(fp_rect
			(start -0.925 -0.47)
			(end 0.925 0.47)
			(stroke
				(width 0.05)
				(type default)
			)
			(fill no)
			(layer "F.CrtYd")
		)
		(fp_rect
			(start -0.5 -0.25)
			(end 0.5 0.25)
			(stroke
				(width 0.15)
				(type solid)
			)
			(fill no)
			(layer "F.Fab")
		)
		(fp_text user "${REFERENCE}"
			(at -0.95 3.168 270)
			(layer "F.Fab")
			(effects
				(font
					(size 0.7 0.7)
					(thickness 0.15)
				)
				(justify left bottom)
			)
		)
		(fp_text user "Author: Antmicro"
			(at -0.95 4.169 270)
			(layer "F.Fab")
			(effects
				(font
					(size 0.7 0.7)
					(thickness 0.15)
				)
				(justify left bottom)
			)
		)
		(fp_text user "License: Apache-2.0"
			(at -0.95 5.169 270)
			(layer "F.Fab")
			(effects
				(font
					(size 0.7 0.7)
					(thickness 0.15)
				)
				(justify left bottom)
			)
		)
		(pad "1" smd roundrect
			(at -0.48 0 270)
			(size 0.59 0.64)
			(layers "F.Cu" "F.Mask" "F.Paste")
			(roundrect_rratio 0.25)
			(net 388 "/X710 flash memory/~{WP}")
			(pintype "passive")
		)
		(pad "2" smd roundrect
			(at 0.48 0 270)
			(size 0.59 0.64)
			(layers "F.Cu" "F.Mask" "F.Paste")
			(roundrect_rratio 0.25)
			(net 343 "/X710 flash memory/+3V3_FLASH")
			(pintype "passive")
		)
	)
)
